# S9S_MB_2U (Grand Teton) — schematic netlist excerpt (pin names and nets, part order shuffled) for the footprints in the layout excerpt that follows; sources: Cadence DE-HDL packaged netlist, KiCad conversion of 03242023_DA0F0TMBIJ0_F0T_Motherboard_J_brd_V01_OCP.brd

PC1221  Q_CAP  0.1UF 25V 10% X7R  pkg 0402  page 262 : A = P1V05_PCH_AUX_REF ; B = SH_P1V05_PCH_AUX_N
PR3919  Q_RES  0 5% CHIP  pkg 0402LF  page 302 : A = HSC_D_OC_1 ; B = HSC_D_OC_R

(kicad_pcb
	(version 20260206)
	(generator "pcbnew")
	(generator_version "10.0")
	(general
		(thickness 1.6)
		(legacy_teardrops no)
	)
	(paper "A4")
	(title_block
		(title "03242023_DA0F0TMBIJ0_F0T_Motherboard_J_brd_V01_OCP.brd")
		(comment 1 "Grand Teton / footprints 3425-3426 of 6105")
	)
	(layers
		(0 "F.Cu" signal "TOP")
		(4 "In1.Cu" signal "GND")
		(6 "In2.Cu" signal "IN1")
		(8 "In3.Cu" signal "GND1")
		(10 "In4.Cu" signal "IN2")
		(12 "In5.Cu" signal "GND2")
		(14 "In6.Cu" signal "IN3")
		(16 "In7.Cu" signal "GND3")
		(18 "In8.Cu" signal "VCC")
		(20 "In9.Cu" signal "VCC1")
		(22 "In10.Cu" signal "GND4")
		(24 "In11.Cu" signal "IN4")
		(26 "In12.Cu" signal "GND5")
		(28 "In13.Cu" signal "IN5")
		(30 "In14.Cu" signal "GND6")
		(32 "In15.Cu" signal "IN6")
		(34 "In16.Cu" signal "GND7")
		(2 "B.Cu" signal "BOTTOM")
		(9 "F.Adhes" user "F.Adhesive")
		(11 "B.Adhes" user "B.Adhesive")
		(13 "F.Paste" user "Package Geometry/Pastemask Top")
		(15 "B.Paste" user "Package Geometry/Pastemask Bottom")
		(5 "F.SilkS" user "Ref Des/Silkscreen Top")
		(7 "B.SilkS" user "Ref Des/Silkscreen Bottom")
		(1 "F.Mask" user "Board Geometry/Soldermask Top")
		(3 "B.Mask" user "Board Geometry/Soldermask Bottom")
		(17 "Dwgs.User" user "User.Drawings")
		(19 "Cmts.User" user "User.Comments")
		(21 "Eco1.User" user "User.Eco1")
		(23 "Eco2.User" user "User.Eco2")
		(25 "Edge.Cuts" user "Board Geometry/Outline")
		(27 "Margin" user)
		(31 "F.CrtYd" user "Package Geometry/Place Bound Top")
		(29 "B.CrtYd" user "Package Geometry/Place Bound Bottom")
		(35 "F.Fab" user "Ref Des/Assembly Top")
		(33 "B.Fab" user "Ref Des/Assembly Bottom")
	)
	(footprint ""
		(layer "F.Cu")
		(at 205.397608 -400.759422)
		(property "Reference" "PR3919"
			(at 0 0 0)
			(layer "F.SilkS")
			(hide yes)
			(effects
				(font
					(size 1.27 1.27)
				)
			)
		)
		(property "Value" ""
			(at 0 0 0)
			(layer "F.Fab")
			(effects
				(font
					(size 1.27 1.27)
				)
			)
		)
		(duplicate_pad_numbers_are_jumpers no)
		(fp_line
			(start -0.7874 -0.4064)
			(end 0.7874 -0.4064)
			(stroke
				(width 0.1524)
				(type default)
			)
			(layer "F.SilkS")
		)
		(fp_line
			(start -0.7874 0.4064)
			(end -0.7874 -0.4064)
			(stroke
				(width 0.1524)
				(type default)
			)
			(layer "F.SilkS")
		)
		(fp_line
			(start 0.7874 -0.4064)
			(end 0.7874 0.4064)
			(stroke
				(width 0.1524)
				(type default)
			)
			(layer "F.SilkS")
		)
		(fp_line
			(start 0.7874 0.4064)
			(end -0.7874 0.4064)
			(stroke
				(width 0.1524)
				(type default)
			)
			(layer "F.SilkS")
		)
		(fp_line
			(start -0.67945 -0.305054)
			(end -0.12065 -0.305054)
			(stroke
				(width 0.1)
				(type default)
			)
			(layer "F.Fab")
		)
		(fp_line
			(start -0.67945 0.3048)
			(end -0.67945 -0.305054)
			(stroke
				(width 0.1)
				(type default)
			)
			(layer "F.Fab")
		)
		(fp_line
			(start -0.12065 -0.305054)
			(end -0.12065 -0.2794)
			(stroke
				(width 0.1)
				(type default)
			)
			(layer "F.Fab")
		)
		(fp_line
			(start -0.12065 -0.2794)
			(end 0.12065 -0.2794)
			(stroke
				(width 0.1)
				(type default)
			)
			(layer "F.Fab")
		)
		(fp_line
			(start -0.12065 0.2794)
			(end -0.12065 0.3048)
			(stroke
				(width 0.1)
				(type default)
			)
			(layer "F.Fab")
		)
		(fp_line
			(start -0.12065 0.3048)
			(end -0.67945 0.3048)
			(stroke
				(width 0.1)
				(type default)
			)
			(layer "F.Fab")
		)
		(fp_line
			(start 0.120396 0.2794)
			(end -0.12065 0.2794)
			(stroke
				(width 0.1)
				(type default)
			)
			(layer "F.Fab")
		)
		(fp_line
			(start 0.120396 0.3048)
			(end 0.120396 0.2794)
			(stroke
				(width 0.1)
				(type default)
			)
			(layer "F.Fab")
		)
		(fp_line
			(start 0.12065 -0.3048)
			(end 0.67945 -0.3048)
			(stroke
				(width 0.1)
				(type default)
			)
			(layer "F.Fab")
		)
		(fp_line
			(start 0.12065 -0.2794)
			(end 0.12065 -0.3048)
			(stroke
				(width 0.1)
				(type default)
			)
			(layer "F.Fab")
		)
		(fp_line
			(start 0.67945 -0.3048)
			(end 0.67945 0.3048)
			(stroke
				(width 0.1)
				(type default)
			)
			(layer "F.Fab")
		)
		(fp_line
			(start 0.67945 0.3048)
			(end 0.120396 0.3048)
			(stroke
				(width 0.1)
				(type default)
			)
			(layer "F.Fab")
		)
		(pad "1" smd circle
			(at -0.40005 0)
			(size 0 0)
			(layers "F.Cu" "F.Mask" "F.Paste")
			(net "HSC_D_OC_1")
		)
		(pad "2" smd circle
			(at 0.40005 0)
			(size 0 0)
			(layers "F.Cu" "F.Mask" "F.Paste")
			(net "HSC_D_OC_R")
		)
	)
	(footprint ""
		(layer "F.Cu")
		(at 261.88035 -75.61834 90)
		(property "Reference" "PC1221"
			(at 0 0 90)
			(layer "F.SilkS")
			(hide yes)
			(effects
				(font
					(size 1.27 1.27)
				)
			)
		)
		(property "Value" ""
			(at 0 0 90)
			(layer "F.Fab")
			(effects
				(font
					(size 1.27 1.27)
				)
			)
		)
		(duplicate_pad_numbers_are_jumpers no)
		(fp_line
			(start 0.7874 -0.4064)
			(end 0.7874 0.4064)
			(stroke
				(width 0.1524)
				(type default)
			)
			(layer "F.SilkS")
		)
		(fp_line
			(start -0.7874 -0.4064)
			(end 0.7874 -0.4064)
			(stroke
				(width 0.1524)
				(type default)
			)
			(layer "F.SilkS")
		)
		(fp_line
			(start 0.7874 0.4064)
			(end -0.7874 0.4064)
			(stroke
				(width 0.1524)
				(type default)
			)
			(layer "F.SilkS")
		)
		(fp_line
			(start -0.7874 0.4064)
			(end -0.7874 -0.4064)
			(stroke
				(width 0.1524)
				(type default)
			)
			(layer "F.SilkS")
		)
		(fp_line
			(start -0.12065 -0.305054)
			(end -0.12065 -0.2794)
			(stroke
				(width 0.1)
				(type default)
			)
			(layer "F.Fab")
		)
		(fp_line
			(start -0.67945 -0.305054)
			(end -0.12065 -0.305054)
			(stroke
				(width 0.1)
				(type default)
			)
			(layer "F.Fab")
		)
		(fp_line
			(start 0.67945 -0.3048)
			(end 0.67945 0.3048)
			(stroke
				(width 0.1)
				(type default)
			)
			(layer "F.Fab")
		)
		(fp_line
			(start 0.12065 -0.3048)
			(end 0.67945 -0.3048)
			(stroke
				(width 0.1)
				(type default)
			)
			(layer "F.Fab")
		)
		(fp_line
			(start 0.12065 -0.2794)
			(end 0.12065 -0.3048)
			(stroke
				(width 0.1)
				(type default)
			)
			(layer "F.Fab")
		)
		(fp_line
			(start -0.12065 -0.2794)
			(end 0.12065 -0.2794)
			(stroke
				(width 0.1)
				(type default)
			)
			(layer "F.Fab")
		)
		(fp_line
			(start 0.120396 0.2794)
			(end -0.12065 0.2794)
			(stroke
				(width 0.1)
				(type default)
			)
			(layer "F.Fab")
		)
		(fp_line
			(start -0.12065 0.2794)
			(end -0.12065 0.3048)
			(stroke
				(width 0.1)
				(type default)
			)
			(layer "F.Fab")
		)
		(fp_line
			(start 0.67945 0.3048)
			(end 0.120396 0.3048)
			(stroke
				(width 0.1)
				(type default)
			)
			(layer "F.Fab")
		)
		(fp_line
			(start 0.120396 0.3048)
			(end 0.120396 0.2794)
			(stroke
				(width 0.1)
				(type default)
			)
			(layer "F.Fab")
		)
		(fp_line
			(start -0.12065 0.3048)
			(end -0.67945 0.3048)
			(stroke
				(width 0.1)
				(type default)
			)
			(layer "F.Fab")
		)
		(fp_line
			(start -0.67945 0.3048)
			(end -0.67945 -0.305054)
			(stroke
				(width 0.1)
				(type default)
			)
			(layer "F.Fab")
		)
		(pad "1" smd circle
			(at -0.40005 0 90)
			(size 0 0)
			(layers "F.Cu" "F.Mask" "F.Paste")
			(net "P1V05_PCH_AUX_REF")
		)
		(pad "2" smd circle
			(at 0.40005 0 90)
			(size 0 0)
			(layers "F.Cu" "F.Mask" "F.Paste")
			(net "SH_P1V05_PCH_AUX_N")
		)
	)
)
